FILE_TYPE = CONNECTIVITY;
{Allegro Design Entry HDL 17.2-2016 S081 (4005846) 1/11/2022}
"PAGE_NUMBER" = 28;
0"NC";
1"GND\g";
2"GND\g";
3"GND\g";
4"GND\g";
5"GND\g";
6"GND\g";
7"PVDD11_S3_P0\g";
8"PVDD18_S5_P0\g";
9"PVDD18_S5_P0\g";
10"PVDD18_S5_P0\g";
11"GND\g";
12"XTAL_CPU0_X32K_X2";
13"XTAL_CPU0_X32K_X1";
14"I3C_1_SPD_DDRGL_CPU0_R_SCL";
15"I3C_0_SPD_DDRAF_CPU0_R_SDA";
16"I3C_1_SPD_DDRGL_CPU0_R_SDA";
17"I3C_0_SPD_DDRAF_CPU0_R_SCL";
18"CPU0_FPGA_SPARE_2";
19"CPU0_FPGA_SPARE_3";
20"RST_CPU0_RSMRST_N";
21"CPU0_PWR_GD_OUT";
22"CPU0_SLP_S5_N";
23"CPU0_SLP_S3_N";
24"CPU0_SMERR_N";
25"CPU0_SPD_HOST_CTRL_N";
26"CPU0_NV_SAVE_N";
27"FM_INT_CPU0_HP_UBM_N";
28"XTAL_CPU0_X48M_X1";
29"CPU0_PWR_GOOD";
30"CPU0_FPGA_SPARE_1";
31"CPU0_FPGA_SPARE_0";
32"PWRGD_CPU0_PWROK";
33"IRQ_WAKE_N";
34"CPU0_PWR_BTN_N";
35"RST_CPU0_SYS_N";
36"CPU0_PWR_BTN_N";
37"RST_CPU0_SYS_N";
38"CLK_100M_REF_IN_DP";
39"CLK_100M_REF_IN_DN";
40"CPU1_PWR_GD_IN";
41"CLK_100M_CPU0_CLK11_DN";
42"CLK_100M_CPU0_CLK11_DP";
43"RST_CPU0_RESETL_N";
44"CLK_100M_REF_OUT_DP";
45"CLK_100M_REF_OUT_DN";
46"RST_CPU0_PERST0_N";
47"CPU0_NV_SAVE_N";
48"CPU0_FORCE_SELFREFRESH";
49"CLK_CPU0_RTCCLK";
50"CPU0_PWR_GD_OUT";
51"RST_CPU0_PERST1_N";
52"CLK_100M_CPU0_CLK11_R_DN";
53"CLK_100M_CPU0_CLK11_R_DP";
54"CLK_100M_CPU0_CLK15_DN";
55"CLK_100M_CPU0_CLK15_DP";
56"CLK_100M_CPU0_CLK13_DN";
57"CLK_100M_CPU0_CLK13_DP";
58"SMB_CPU0_SEC_SDA";
59"SMB_CPU0_SEC_SCL";
60"CLK_100M_CPU0_CLK15_R_DN";
61"CLK_100M_CPU0_CLK15_R_DP";
62"CLK_100M_CPU0_CLK13_R_DN";
63"CLK_100M_CPU0_CLK13_R_DP";
64"CPU0_PWR_GOOD";
65"RST_CPU0_RSMRST_N";
66"RST_CPU0_SYS_N";
67"CPU0_PWR_BTN_N";
68"FM_INT_CPU0_HP_UBM_N";
69"I3C_1_SPD_DDRGL_CPU0_R_SDA";
70"I3C_1_SPD_DDRGL_CPU0_R_SCL";
71"I3C_0_SPD_DDRAF_CPU0_R_SDA";
72"I3C_0_SPD_DDRAF_CPU0_R_SCL";
73"XTAL_CPU0_X48M_X2";
74"XTAL_CPU0_X48M_X1";
75"CPU0_NMI_SYNC_FLOOD_N";
76"XTAL_CPU0_X32K_X2";
77"XTAL_CPU0_X32K_X1";
78"CPU0_SLP_S5_N";
79"CPU0_SLP_S3_N";
80"SMB_CPU0_2_R_SCL";
81"SMB_CPU0_2_R_SDA";
82"SMB_CPU0_3_R_SCL";
83"FM_CPU0_SLP_S3_N";
84"FM_CPU0_SLP_S5_N";
85"SMB_CPU0_2_SCL";
86"SMB_CPU0_2_SDA";
87"SMB_CPU0_3_SCL";
88"XTAL_CPU0_X48M_X2";
89"CPU0_SPD_HOST_CTRL_N";
90"BIOS_DEBUG_MODE";
91"SLOT1_BUF_SKU_ID0";
92"SLOT1_BUF_SKU_ID1";
93"CPU0_SMERR_N";
94"CPU0_FPGA_SPARE_3";
95"CPU0_FPGA_SPARE_2";
96"CPU0_FPGA_SPARE_1";
97"CPU0_FPGA_SPARE_0";
98"CPU0_ROM_TYPE_SELECT";
99"SMB_CPU_5_R_SDA";
100"FM_PASSWORD_CLEAR_R_N";
101"FM_BIOS_POST_CMPLT_R_N";
102"SMB_CPU_5_R_SCL";
103"SMB_CPU0_3_R_SDA";
104"SMB_CPU0_4_R_SCL";
105"SMB_CPU0_4_R_SDA";
106"BOOT_RDY_R_H";
107"BOOT_RDY_H";
108"FM_BIOS_POST_CMPLT_N";
109"SMB_CPU0_4_SDA";
110"SMB_CPU0_4_SCL";
111"FM_PASSWORD_CLEAR_N";
112"SMB_CPU_5_SCL";
113"SMB_CPU_5_SDA";
114"SMB_CPU0_3_SDA";
115"BOOT_RDY_H";
116"PWRGD_CPU0_PWROK";
117"RST_CPU0_RESETL_N";
118"CPU0_NMI_SYNC_FLOOD_N";
119"CPU0_FORCE_SELFREFRESH";
120"GND\g";
121"GND\g";
122"GND\g";
%"Q_XTAL_4P_13BI_24GND"
"1","(-5500,1725)","0","pure_quanta","I11";
;
LOCATION"Y2"
$SEC"1"
CDS_SEC"1"
PART_TYPE"SMLF"
MATERIAL"MISC "
VALUE"48MHZ"
PART_NUMBER"BG648000055"
PIN_NAMES_ROTATE"True"
CDS_LMAN_SYM_OUTLINE"-125,175,125,-175"
CDS_LIB"pure_quanta";
"X2"
$PN"3"88;
"G2"
$PN"4"2;
"G1"
$PN"2"1;
"X1"
$PN"1"28;
%"Q_RES"
"2","(-8500,2725)","0","pure_quanta","I119";
;
LOCATION"R425"
$SEC"1"
CDS_SEC"1"
VALUE"1K"
TOLERANCE"5%"
MATERIAL"EMPTY"
WATTAGE"1/16W"
PACK_TYPE"0402LF"
CDS_LIB"pure_quanta"
PART_NUMBER"TMP_QCS21002JB34";
"A"
$PN"1"7;
"B"
$PN"2"17;
%"Q_RES"
"2","(-8850,2725)","0","pure_quanta","I120";
;
LOCATION"R421"
$SEC"1"
CDS_SEC"1"
VALUE"1K"
TOLERANCE"5%"
MATERIAL"EMPTY"
CDS_LIB"pure_quanta"
WATTAGE"1/16W"
PACK_TYPE"0402LF"
PART_NUMBER"TMP_QCS21002JB34";
"A"
$PN"1"7;
"B"
$PN"2"14;
%"Q_RES"
"2","(-8675,2725)","0","pure_quanta","I121";
;
LOCATION"R423"
$SEC"1"
CDS_SEC"1"
TOLERANCE"5%"
VALUE"1K"
MATERIAL"EMPTY"
CDS_LIB"pure_quanta"
WATTAGE"1/16W"
PACK_TYPE"0402LF"
PART_NUMBER"TMP_QCS21002JB34";
"A"
$PN"1"7;
"B"
$PN"2"15;
%"Q_RES"
"2","(-9025,2725)","0","pure_quanta","I123";
;
LOCATION"R420"
$SEC"1"
CDS_SEC"1"
TOLERANCE"5%"
VALUE"1K"
MATERIAL"EMPTY"
CDS_LIB"pure_quanta"
WATTAGE"1/16W"
PACK_TYPE"0402LF"
PART_NUMBER"TMP_QCS21002JB34";
"A"
$PN"1"7;
"B"
$PN"2"16;
%"VCC_CORE"
"1","(-8500,3025)","0","pure_quanta_power","I130";
;
HDL_POWER"PVDD11_S3_P0"
CDS_LIB"pure_quanta_power";
"A"7;
%"UNIVERSAL_GND"
"1","(-5875,1400)","0","pure_quanta_power","I14";
;
CDS_LIB"pure_quanta_power"
HDL_POWER"GND";
"A"1;
%"UNIVERSAL_GND"
"1","(-5075,1375)","0","pure_quanta_power","I15";
;
CDS_LIB"pure_quanta_power"
HDL_POWER"GND";
"A"2;
%"Q_CAP"
"1","(-6150,975)","0","pure_quanta","I16";
;
LOCATION"C213"
$SEC"1"
CDS_SEC"1"
PART_NUMBER"CH-3916TB01"
PACK_TYPE"C0402"
VOLTAGE"50V"
VALUE"3.9P"
TOLERANCE"0.1P"
MATERIAL"NPO"
CDS_LIB"pure_quanta";
"B"
$PN"2"3;
"A"
$PN"1"28;
%"UNIVERSAL_GND"
"1","(-6150,675)","0","pure_quanta_power","I17";
;
CDS_LIB"pure_quanta_power"
HDL_POWER"GND";
"A"3;
%"Q_CAP"
"1","(-4875,975)","0","pure_quanta","I18";
;
LOCATION"C214"
$SEC"1"
CDS_SEC"1"
MATERIAL"NPO"
TOLERANCE"0.1P"
VALUE"3.9P"
PART_NUMBER"CH-3916TB01"
VOLTAGE"50V"
PACK_TYPE"C0402"
CDS_LIB"pure_quanta";
"B"
$PN"2"4;
"A"
$PN"1"88;
%"GENOA_SP5"
"21","(-4275,4450)","0","pure_quanta","I186";
;
LOCATION"U25"
$SEC"21"
CDS_SEC"21"
PART_TYPE"SMLF"
MATERIAL"IO"
VALUE"SOCKET6096_13568-001"
PART_NUMBER"DGA^6000030"
CDS_LIB"pure_quanta"
CDS_LMAN_SYM_OUTLINE"-1100,1800,1100,-1800"
NEEDS_NO_SIZE"TRUE";
"AGPIO7"
$PN"DH4"0;
"NMI_SYNC_FLOOD_L"
$PN"DJ31"75;
"SEC_SCL||AGPIO262"
$PN"B14"59;
"SEC_SDA||AGPIO263"
$PN"D14"58;
"AGPIO257||SGPIO1_CLK||CLK_REQ01_L"
$PN"C14"0;
"PWROK||SVI_RST_L"
$PN"D69"32;
"AGPIO6||DEVSLP1||SATA_ZP1_L"
$PN"DE40"96;
"AGPIO5||DEVSLP0||SATA_ZP0_L"
$PN"DF40"97;
"GENINT_L||PM_INTR_L||UBM_CPRSNT_CHANGE_DET_L||AGPIO89"
$PN"DJ35"68;
"AGPIO22"
$PN"DE32"92;
"AGPIO88"
$PN"DJ29"101;
"AGPIO21"
$PN"DF33"91;
"AGPIO87"
$PN"DG11"0;
"AGPIO109"
$PN"DG32"98;
"AGPIO107"
$PN"DG31"0;
"AGPIO106"
$PN"DF31"0;
"AGPIO105"
$PN"DE30"90;
"AGPIO104"
$PN"DH30"106;
"RESET_L \B"
$PN"B67"43;
"REFCLK100SSC_N||GPP_CLK10N"
$PN"A20"45;
"REFCLK100SSC_P||GPP_CLK10P"
$PN"A19"44;
"SMERR_L||AGPIO24"
$PN"DJ11"93;
"I2C5_SDA||BMC_SDA||SMBUS1_SDA||AGPIO20"
$PN"DJ20"99;
"I2C5_SCL||BMC_SCL||SMBUS1_SCL||AGPIO19"
$PN"DJ21"102;
"I2C4_SDA||HP_SDA||UBM_SDA||AGPIO14"
$PN"DH12"105;
"I2C4_SCL||HP_SCL||UBM_SCL||AGPIO13"
$PN"DG12"104;
"I3C3_SCL||I2C3_SCL||SPD3_SCL||AGPIO151"
$PN"A4"82;
"I3C1_SDA||I2C1_SDA||SPD1_SDA||AGPIO148"
$PN"A5"69;
"AGPIO116||CLK_REQ12_L"
$PN"DH15"94;
"PWRGD_OUT||AGPIO12"
$PN"DH36"50;
"AGPIO259||SGPIO3_CLK"
$PN"B16"0;
"I3C0_SCL||I2C0_SCL||SPD0_SCL||SMBUS0_SCL||AGPIO145"
$PN"A71"72;
"I3C2_SCL||I2C2_SCL||SPD2_SCL||AGPIO149"
$PN"C72"80;
"I3C1_SCL||I2C1_SCL||SPD1_SCL||AGPIO147"
$PN"C7"70;
"I3C0_SDA||I2C0_SDA||SPD0_SDA||SMBUS0_SDA||AGPIO146"
$PN"B71"71;
"AGPIO115||CLK_REQ11_L"
$PN"DH16"95;
"PCIE_RST0_L||AGPIO266"
$PN"D18"46;
"AGPIO256||SGPIO0_CLK"
$PN"A14"0;
"AGPIO258||SGPIO2_CLK||CLK_REQ02_L"
$PN"A13"0;
"I3C3_SDA||I2C3_SDA||SPD3_SDA||AGPIO152"
$PN"B4"103;
"SGPIO_DATAOUT||AGPIO260"
$PN"D15"0;
"I3C2_SDA||I2C2_SDA||SPD2_SDA||AGPIO150"
$PN"B72"81;
"SGPIO_LOAD||AGPIO261"
$PN"B15"0;
"PCIE_RST1_L||AGPIO26"
$PN"DG36"51;
"AGPIO3||SPD_HOST_CTRL_L"
$PN"DE36"89;
"AGPIO4||SATA_ACT_L"
$PN"DF36"100;
"GPP_CLK11P"
$PN"DJ41"53;
"GPP_CLK01P"
$PN"A8"0;
"GPP_CLK12P"
$PN"DJ45"0;
"GPP_CLK02P"
$PN"B6"0;
"GPP_CLK11N"
$PN"DJ42"52;
"GPP_CLK13P"
$PN"DJ53"63;
"GPP_CLK01N"
$PN"A7"0;
"GPP_CLK03P"
$PN"A10"0;
"GPP_CLK12N"
$PN"DJ44"0;
"GPP_CLK14P"
$PN"DJ48"0;
"GPP_CLK02N"
$PN"C6"0;
"GPP_CLK04P"
$PN"B12"0;
"GPP_CLK13N"
$PN"DJ54"62;
"GPP_CLK15P"
$PN"DJ51"61;
"GPP_CLK03N"
$PN"A11"0;
"GPP_CLK05P"
$PN"B9"0;
"GPP_CLK14N"
$PN"DJ47"0;
"GPP_CLK04N"
$PN"C12"0;
"GPP_CLK15N"
$PN"DJ50"60;
"GPP_CLK05N"
$PN"C9"0;
"RTCCLK"
$PN"DH9"49;
"FORCE_SELFREFRESH"
$PN"B63"48;
"NV_SAVE_L"
$PN"B64"47;
"PWR_BTN_L||AGPIO0"
$PN"DH7"67;
"X48M_X2"
$PN"DJ16"73;
"X48M_X1"
$PN"DJ17"74;
"X32K_X2"
$PN"DJ13"76;
"X32K_X1"
$PN"DJ14"77;
"WAKE_L||AGPIO2"
$PN"DJ10"33;
"SYS_RESET_L||AGPIO1"
$PN"DH6"66;
"SLP_S5_L"
$PN"DG4"78;
"SLP_S3_L"
$PN"DJ5"79;
"RSMRST_L \B"
$PN"DG10"65;
"PWR_GOOD"
$PN"DJ8"64;
%"UNIVERSAL_GND"
"1","(-4875,675)","0","pure_quanta_power","I19";
;
CDS_LIB"pure_quanta_power"
HDL_POWER"GND";
"A"4;
%"Q_RES"
"1","(-5500,1200)","0","pure_quanta","I20";
;
LOCATION"R432"
$SEC"1"
CDS_SEC"1"
MATERIAL"CHIP"
TOLERANCE"5%"
PACK_TYPE"0402LF"
WATTAGE"1/16W"
VALUE"10M"
PART_NUMBER"CS61002JB23"
CDS_LIB"pure_quanta";
"B"
$PN"2"88;
"A"
$PN"1"28;
%"Q_RES"
"1","(-1725,6100)","0","pure_quanta","I206";
;
LOCATION"R435"
$SEC"1"
CDS_SEC"1"
VALUE"0"
CDS_LIB"pure_quanta"
WATTAGE"1/16W"
MATERIAL"CHIP"
TOLERANCE"5%"
PART_NUMBER"CS00002JB38"
PACK_TYPE"0402LF";
"B"
$PN"2"38;
"A"
$PN"1"44;
%"Q_RES"
"1","(-1725,6050)","0","pure_quanta","I207";
;
LOCATION"R436"
$SEC"1"
CDS_SEC"1"
VALUE"0"
CDS_LIB"pure_quanta"
WATTAGE"1/16W"
MATERIAL"CHIP"
TOLERANCE"5%"
PART_NUMBER"CS00002JB38"
PACK_TYPE"0402LF";
"B"
$PN"2"39;
"A"
$PN"1"45;
%"Q_RES"
"1","(-2100,5600)","0","pure_quanta","I224";
;
LOCATION"R434"
$SEC"1"
CDS_SEC"1"
VALUE"33"
CDS_LIB"pure_quanta"
WATTAGE"1/16W"
MATERIAL"CHIP"
TOLERANCE"5%"
PART_NUMBER"CS03302JB29"
PACK_TYPE"0402LF";
"B"
$PN"2"40;
"A"
$PN"1"50;
%"Q_RES"
"1","(-6775,4100)","2","pure_quanta","I285";
;
LOCATION"R29"
$SEC"1"
CDS_SEC"1"
VALUE"0"
CDS_LIB"pure_quanta"
WATTAGE"1/16W"
MATERIAL"CHIP"
TOLERANCE"5%"
PART_NUMBER"CS00002JB38"
PACK_TYPE"0402LF";
"B"
$PN"2"87;
"A"
$PN"1"82;
%"Q_RES"
"1","(-6775,4050)","2","pure_quanta","I286";
;
LOCATION"R30"
$SEC"1"
CDS_SEC"1"
VALUE"0"
CDS_LIB"pure_quanta"
WATTAGE"1/16W"
MATERIAL"CHIP"
TOLERANCE"5%"
PART_NUMBER"CS00002JB38"
PACK_TYPE"0402LF";
"B"
$PN"2"114;
"A"
$PN"1"103;
%"Q_RES"
"1","(-6775,4150)","2","pure_quanta","I291";
;
LOCATION"R28"
$SEC"1"
CDS_SEC"1"
VALUE"0"
CDS_LIB"pure_quanta"
WATTAGE"1/16W"
MATERIAL"CHIP"
TOLERANCE"5%"
PART_NUMBER"CS00002JB38"
PACK_TYPE"0402LF";
"B"
$PN"2"86;
"A"
$PN"1"81;
%"Q_RES"
"1","(-6775,4200)","2","pure_quanta","I292";
;
LOCATION"R27"
$SEC"1"
CDS_SEC"1"
VALUE"0"
CDS_LIB"pure_quanta"
WATTAGE"1/16W"
MATERIAL"CHIP"
TOLERANCE"5%"
PART_NUMBER"CS00002JB38"
PACK_TYPE"0402LF";
"B"
$PN"2"85;
"A"
$PN"1"80;
%"Q_RES"
"1","(-6775,3850)","2","pure_quanta","I299";
;
LOCATION"R213"
$SEC"1"
CDS_SEC"1"
VALUE"0"
CDS_LIB"pure_quanta"
WATTAGE"1/16W"
MATERIAL"CHIP"
TOLERANCE"5%"
PART_NUMBER"CS00002JB38"
PACK_TYPE"0402LF";
"B"
$PN"2"113;
"A"
$PN"1"99;
%"Q_CRYSTAL"
"1","(-3275,1825)","0","pure_quanta","I3";
;
LOCATION"Y3"
$SEC"1"
CDS_SEC"1"
VALUE"32.768KHZ"
MATERIAL"IC"
PART_NUMBER"BG632768012"
PACK_TYPE"SMLF"
CDS_LIB"pure_quanta"
NEEDS_NO_SIZE"TRUE";
"2"
$PN"2"12;
"1"
$PN"1"13;
%"Q_RES"
"1","(-6775,3900)","2","pure_quanta","I300";
;
LOCATION"R212"
$SEC"1"
CDS_SEC"1"
VALUE"0"
CDS_LIB"pure_quanta"
WATTAGE"1/16W"
MATERIAL"CHIP"
TOLERANCE"5%"
PART_NUMBER"CS00002JB38"
PACK_TYPE"0402LF";
"B"
$PN"2"112;
"A"
$PN"1"102;
%"UNIVERSAL_POWER"
"1","(-7350,2150)","0","pure_quanta_power","I304";
;
HDL_POWER"PVDD18_S5_P0"
CDS_LIB"pure_quanta_power";
"A"8;
%"Q_RES"
"1","(-7700,2000)","0","pure_quanta","I305";
;
LOCATION"R438"
$SEC"1"
CDS_SEC"1"
VALUE"4.7K"
CDS_LIB"pure_quanta"
WATTAGE"1/16W"
MATERIAL"CHIP"
TOLERANCE"5%"
PART_NUMBER"TMP_QCS24702JB38"
PACK_TYPE"0402LF";
"B"
$PN"2"8;
"A"
$PN"1"119;
%"Q_RES"
"1","(-7700,1650)","0","pure_quanta","I310";
;
LOCATION"R445"
$SEC"1"
CDS_SEC"1"
VALUE"4.7K"
CDS_LIB"pure_quanta"
WATTAGE"1/16W"
MATERIAL"CHIP"
TOLERANCE"5%"
PART_NUMBER"TMP_QCS24702JB38"
PACK_TYPE"0402LF";
"B"
$PN"2"8;
"A"
$PN"1"30;
%"Q_RES"
"1","(-7700,1700)","0","pure_quanta","I311";
;
LOCATION"R444"
$SEC"1"
CDS_SEC"1"
VALUE"4.7K"
CDS_LIB"pure_quanta"
WATTAGE"1/16W"
MATERIAL"CHIP"
TOLERANCE"5%"
PART_NUMBER"TMP_QCS24702JB38"
PACK_TYPE"0402LF";
"B"
$PN"2"8;
"A"
$PN"1"31;
%"Q_RES"
"1","(-7700,1600)","0","pure_quanta","I312";
;
LOCATION"R446"
$SEC"1"
CDS_SEC"1"
VALUE"4.7K"
CDS_LIB"pure_quanta"
WATTAGE"1/16W"
MATERIAL"CHIP"
TOLERANCE"5%"
PART_NUMBER"TMP_QCS24702JB38"
PACK_TYPE"0402LF";
"B"
$PN"2"8;
"A"
$PN"1"18;
%"Q_RES"
"1","(-7700,1500)","0","pure_quanta","I313";
;
LOCATION"R448"
$SEC"1"
CDS_SEC"1"
MATERIAL"EMPTY"
VALUE"4.7K"
CDS_LIB"pure_quanta"
WATTAGE"1/16W"
TOLERANCE"5%"
PART_NUMBER"TMP_QCS24702JB38"
PACK_TYPE"0402LF";
"B"
$PN"2"8;
"A"
$PN"1"22;
%"Q_RES"
"1","(-7700,1550)","0","pure_quanta","I314";
;
LOCATION"R447"
$SEC"1"
CDS_SEC"1"
VALUE"4.7K"
CDS_LIB"pure_quanta"
WATTAGE"1/16W"
MATERIAL"CHIP"
TOLERANCE"5%"
PART_NUMBER"TMP_QCS24702JB38"
PACK_TYPE"0402LF";
"B"
$PN"2"8;
"A"
$PN"1"19;
%"Q_RES"
"1","(-7700,1450)","0","pure_quanta","I315";
;
LOCATION"R449"
$SEC"1"
CDS_SEC"1"
MATERIAL"EMPTY"
VALUE"4.7K"
CDS_LIB"pure_quanta"
WATTAGE"1/16W"
TOLERANCE"5%"
PART_NUMBER"TMP_QCS24702JB38"
PACK_TYPE"0402LF";
"B"
$PN"2"8;
"A"
$PN"1"23;
%"Q_RES"
"1","(-7700,1400)","0","pure_quanta","I316";
;
LOCATION"R450"
$SEC"1"
CDS_SEC"1"
VALUE"4.7K"
CDS_LIB"pure_quanta"
WATTAGE"1/16W"
MATERIAL"CHIP"
TOLERANCE"5%"
PART_NUMBER"TMP_QCS24702JB38"
PACK_TYPE"0402LF";
"B"
$PN"2"8;
"A"
$PN"1"24;
%"Q_RES"
"1","(-7700,1350)","0","pure_quanta","I329";
;
LOCATION"R451"
$SEC"1"
CDS_SEC"1"
VALUE"4.7K"
CDS_LIB"pure_quanta"
WATTAGE"1/16W"
MATERIAL"CHIP"
TOLERANCE"5%"
PART_NUMBER"TMP_QCS24702JB38"
PACK_TYPE"0402LF";
"B"
$PN"2"8;
"A"
$PN"1"25;
%"Q_RES"
"1","(-7700,1300)","0","pure_quanta","I335";
;
LOCATION"R452"
$SEC"1"
CDS_SEC"1"
VALUE"4.7K"
CDS_LIB"pure_quanta"
WATTAGE"1/16W"
MATERIAL"CHIP"
TOLERANCE"5%"
PART_NUMBER"TMP_QCS24702JB38"
PACK_TYPE"0402LF";
"B"
$PN"2"8;
"A"
$PN"1"26;
%"Q_RES"
"1","(-7325,825)","1","pure_quanta","I340";
;
LOCATION"R288"
$SEC"1"
CDS_SEC"1"
MATERIAL"EMPTY"
VALUE"4.7K"
CDS_LIB"pure_quanta"
WATTAGE"1/16W"
TOLERANCE"5%"
PART_NUMBER"TMP_QCS24702JB38"
PACK_TYPE"0402LF";
"B"
$PN"2"9;
"A"
$PN"1"21;
%"UNIVERSAL_POWER"
"1","(-7325,1025)","0","pure_quanta_power","I341";
;
HDL_POWER"PVDD18_S5_P0"
CDS_LIB"pure_quanta_power";
"A"9;
%"Q_RES"
"1","(-7550,825)","1","pure_quanta","I342";
;
LOCATION"R276"
$SEC"1"
CDS_SEC"1"
VALUE"4.7K"
MATERIAL"CHIP"
PACK_TYPE"0402LF"
PART_NUMBER"TMP_QCS24702JB38"
TOLERANCE"5%"
WATTAGE"1/16W"
CDS_LIB"pure_quanta";
"B"
$PN"2"9;
"A"
$PN"1"29;
%"UNIVERSAL_GND"
"1","(-7325,325)","0","pure_quanta_power","I343";
;
CDS_LIB"pure_quanta_power"
HDL_POWER"GND";
"A"122;
%"Q_RES"
"1","(-7325,475)","1","pure_quanta","I344";
;
LOCATION"R440"
$SEC"1"
CDS_SEC"1"
MATERIAL"EMPTY"
VALUE"4.7K"
CDS_LIB"pure_quanta"
WATTAGE"1/16W"
TOLERANCE"5%"
PART_NUMBER"TMP_QCS24702JB38"
PACK_TYPE"0402LF";
"B"
$PN"2"21;
"A"
$PN"1"122;
%"Q_RES"
"1","(-7550,475)","1","pure_quanta","I345";
;
LOCATION"R287"
$SEC"1"
CDS_SEC"1"
MATERIAL"EMPTY"
VALUE"4.7K"
CDS_LIB"pure_quanta"
WATTAGE"1/16W"
TOLERANCE"5%"
PART_NUMBER"TMP_QCS24702JB38"
PACK_TYPE"0402LF";
"B"
$PN"2"29;
"A"
$PN"1"121;
%"UNIVERSAL_GND"
"1","(-7550,325)","0","pure_quanta_power","I346";
;
CDS_LIB"pure_quanta_power"
HDL_POWER"GND";
"A"121;
%"Q_RES"
"1","(-7825,850)","1","pure_quanta","I347";
;
LOCATION"R581"
$SEC"1"
CDS_SEC"1"
VALUE"4.7K"
MATERIAL"EMPTY"
CDS_LIB"pure_quanta"
WATTAGE"1/16W"
TOLERANCE"5%"
PART_NUMBER"TMP_QCS24702JB38"
PACK_TYPE"0402LF";
"B"
$PN"2"9;
"A"
$PN"1"20;
%"Q_RES"
"1","(-7825,500)","1","pure_quanta","I348";
;
LOCATION"R582"
$SEC"1"
CDS_SEC"1"
MATERIAL"EMPTY"
VALUE"4.7K"
CDS_LIB"pure_quanta"
WATTAGE"1/16W"
TOLERANCE"5%"
PART_NUMBER"TMP_QCS24702JB38"
PACK_TYPE"0402LF";
"B"
$PN"2"20;
"A"
$PN"1"120;
%"UNIVERSAL_GND"
"1","(-7825,350)","0","pure_quanta_power","I349";
;
CDS_LIB"pure_quanta_power"
HDL_POWER"GND";
"A"120;
%"Q_RES"
"1","(-2050,4100)","0","pure_quanta","I357";
;
LOCATION"R256"
$SEC"1"
CDS_SEC"1"
VALUE"0"
CDS_LIB"pure_quanta"
WATTAGE"1/16W"
MATERIAL"CHIP"
TOLERANCE"5%"
PART_NUMBER"CS00002JB38"
PACK_TYPE"0402LF";
"B"
$PN"2"41;
"A"
$PN"1"52;
%"Q_RES"
"1","(-2050,4150)","0","pure_quanta","I358";
;
LOCATION"R206"
$SEC"1"
CDS_SEC"1"
VALUE"0"
CDS_LIB"pure_quanta"
WATTAGE"1/16W"
MATERIAL"CHIP"
TOLERANCE"5%"
PART_NUMBER"CS00002JB38"
PACK_TYPE"0402LF";
"B"
$PN"2"42;
"A"
$PN"1"53;
%"Q_RES"
"1","(-2050,3800)","0","pure_quanta","I363";
;
LOCATION"R746"
$SEC"1"
CDS_SEC"1"
VALUE"0"
CDS_LIB"pure_quanta"
WATTAGE"1/16W"
MATERIAL"CHIP"
TOLERANCE"5%"
PART_NUMBER"CS00002JB38"
PACK_TYPE"0402LF";
"B"
$PN"2"56;
"A"
$PN"1"62;
%"Q_RES"
"1","(-2050,3850)","0","pure_quanta","I364";
;
LOCATION"R636"
$SEC"1"
CDS_SEC"1"
VALUE"0"
CDS_LIB"pure_quanta"
WATTAGE"1/16W"
MATERIAL"CHIP"
TOLERANCE"5%"
PART_NUMBER"CS00002JB38"
PACK_TYPE"0402LF";
"B"
$PN"2"57;
"A"
$PN"1"63;
%"Q_RES"
"1","(-2050,3500)","0","pure_quanta","I367";
;
LOCATION"R1344"
$SEC"1"
CDS_SEC"1"
VALUE"0"
CDS_LIB"pure_quanta"
WATTAGE"1/16W"
MATERIAL"CHIP"
TOLERANCE"5%"
PART_NUMBER"CS00002JB38"
PACK_TYPE"0402LF";
"B"
$PN"2"54;
"A"
$PN"1"60;
%"Q_RES"
"1","(-2050,3550)","0","pure_quanta","I368";
;
LOCATION"R1044"
$SEC"1"
CDS_SEC"1"
VALUE"0"
CDS_LIB"pure_quanta"
WATTAGE"1/16W"
MATERIAL"CHIP"
TOLERANCE"5%"
PART_NUMBER"CS00002JB38"
PACK_TYPE"0402LF";
"B"
$PN"2"55;
"A"
$PN"1"61;
%"Q_RES"
"1","(-6300,3000)","2","pure_quanta","I370";
;
LOCATION"R939"
$SEC"1"
CDS_SEC"1"
VALUE"0"
CDS_LIB"pure_quanta"
WATTAGE"1/16W"
MATERIAL"CHIP"
TOLERANCE"5%"
PART_NUMBER"CS00002JB38"
PACK_TYPE"0402LF";
"B"
$PN"2"108;
"A"
$PN"1"101;
%"Q_RES"
"1","(-6300,2950)","2","pure_quanta","I371";
;
LOCATION"R940"
$SEC"1"
CDS_SEC"1"
VALUE"0"
CDS_LIB"pure_quanta"
WATTAGE"1/16W"
MATERIAL"CHIP"
TOLERANCE"5%"
PART_NUMBER"CS00002JB38"
PACK_TYPE"0402LF";
"B"
$PN"2"107;
"A"
$PN"1"106;
%"Q_RES"
"1","(-7700,2050)","0","pure_quanta","I373";
;
LOCATION"R938"
$SEC"1"
CDS_SEC"1"
VALUE"4.7K"
CDS_LIB"pure_quanta"
WATTAGE"1/16W"
MATERIAL"CHIP"
TOLERANCE"5%"
PART_NUMBER"TMP_QCS24702JB38"
PACK_TYPE"0402LF";
"B"
$PN"2"8;
"A"
$PN"1"115;
%"Q_RES"
"1","(-6300,3400)","2","pure_quanta","I378";
;
LOCATION"R1205"
$SEC"1"
CDS_SEC"1"
VALUE"0"
CDS_LIB"pure_quanta"
WATTAGE"1/16W"
MATERIAL"CHIP"
TOLERANCE"5%"
PART_NUMBER"CS00002JB38"
PACK_TYPE"0402LF";
"B"
$PN"2"111;
"A"
$PN"1"100;
%"Q_RES"
"2","(-8525,6125)","0","pure_quanta","I380";
;
LOCATION"R424"
$SEC"1"
CDS_SEC"1"
PART_NUMBER"CS22202JB07"
VALUE"2.2K"
CDS_LIB"pure_quanta"
WATTAGE"1/16W"
MATERIAL"CHIP"
TOLERANCE"5%"
PACK_TYPE"0402LF";
"A"
$PN"1"10;
"B"
$PN"2"36;
%"Q_RES"
"1","(-7700,1250)","0","pure_quanta","I381";
;
LOCATION"R207"
$SEC"1"
CDS_SEC"1"
VALUE"2.2K"
CDS_LIB"pure_quanta"
WATTAGE"1/16W"
MATERIAL"CHIP"
TOLERANCE"5%"
PART_NUMBER"CS22202JB07"
PACK_TYPE"0402LF";
"B"
$PN"2"8;
"A"
$PN"1"27;
%"Q_RES"
"1","(-7700,1750)","0","pure_quanta","I383";
;
LOCATION"R443"
$SEC"1"
CDS_SEC"1"
VALUE"1K"
CDS_LIB"pure_quanta"
WATTAGE"1/16W"
MATERIAL"CHIP"
TOLERANCE"5%"
PART_NUMBER"TMP_QCS21002JB34"
PACK_TYPE"0402LF";
"B"
$PN"2"8;
"A"
$PN"1"116;
%"Q_RES"
"1","(-7700,1800)","0","pure_quanta","I384";
;
LOCATION"R442"
$SEC"1"
CDS_SEC"1"
VALUE"1K"
CDS_LIB"pure_quanta"
WATTAGE"1/16W"
MATERIAL"CHIP"
TOLERANCE"5%"
PART_NUMBER"TMP_QCS21002JB34"
PACK_TYPE"0402LF";
"B"
$PN"2"8;
"A"
$PN"1"117;
%"Q_RES"
"1","(-7700,1850)","0","pure_quanta","I385";
;
LOCATION"R441"
$SEC"1"
CDS_SEC"1"
VALUE"2.2K"
CDS_LIB"pure_quanta"
WATTAGE"1/16W"
MATERIAL"CHIP"
TOLERANCE"5%"
PART_NUMBER"CS22202JB07"
PACK_TYPE"0402LF";
"B"
$PN"2"8;
"A"
$PN"1"118;
%"Q_RES"
"1","(-6425,5700)","0","pure_quanta","I386";
;
LOCATION"R249"
$SEC"1"
CDS_SEC"1"
VALUE"33"
CDS_LIB"pure_quanta"
BOM_COST"MEM"
WATTAGE"1/16W"
MATERIAL"CHIP"
TOLERANCE"5%"
PART_NUMBER"CS03302JB29"
PACK_TYPE"0402LF"
ROOM"RST_CPU0_PLD_TO_DIMM";
"B"
$PN"2"79;
"A"
$PN"1"83;
%"Q_RES"
"1","(-6425,5750)","0","pure_quanta","I387";
;
LOCATION"R248"
$SEC"1"
CDS_SEC"1"
VALUE"33"
CDS_LIB"pure_quanta"
BOM_COST"MEM"
WATTAGE"1/16W"
MATERIAL"CHIP"
TOLERANCE"5%"
PART_NUMBER"CS03302JB29"
PACK_TYPE"0402LF"
ROOM"RST_CPU0_PLD_TO_DIMM";
"B"
$PN"2"78;
"A"
$PN"1"84;
%"UNIVERSAL_GND"
"1","(-3825,800)","0","pure_quanta_power","I4";
;
CDS_LIB"pure_quanta_power"
HDL_POWER"GND";
"A"5;
%"Q_CAP"
"1","(-3825,1125)","0","pure_quanta","I5";
;
LOCATION"C215"
$SEC"1"
CDS_SEC"1"
PART_NUMBER"TMP_QCH0106F0B00"
TOLERANCE"1%"
MATERIAL"NPO"
PACK_TYPE"0402"
VOLTAGE"50V"
VALUE"10PF"
CDS_LIB"pure_quanta";
"B"
$PN"2"5;
"A"
$PN"1"13;
%"Q_RES"
"1","(-6775,3950)","2","pure_quanta","I54";
;
LOCATION"R431"
$SEC"1"
CDS_SEC"1"
VALUE"0"
CDS_LIB"pure_quanta"
WATTAGE"1/16W"
MATERIAL"CHIP"
TOLERANCE"5%"
PART_NUMBER"CS00002JB38"
PACK_TYPE"0402LF";
"B"
$PN"2"109;
"A"
$PN"1"105;
%"Q_RES"
"1","(-6775,4000)","2","pure_quanta","I57";
;
LOCATION"R430"
$SEC"1"
CDS_SEC"1"
VALUE"0"
CDS_LIB"pure_quanta"
WATTAGE"1/16W"
MATERIAL"CHIP"
TOLERANCE"5%"
PART_NUMBER"CS00002JB38"
PACK_TYPE"0402LF";
"B"
$PN"2"110;
"A"
$PN"1"104;
%"Q_CAP"
"1","(-2725,1150)","0","pure_quanta","I6";
;
LOCATION"C216"
$SEC"1"
CDS_SEC"1"
PART_NUMBER"TMP_QCH0106F0B00"
TOLERANCE"1%"
MATERIAL"NPO"
PACK_TYPE"0402"
VOLTAGE"50V"
VALUE"10PF"
CDS_LIB"pure_quanta";
"B"
$PN"2"6;
"A"
$PN"1"12;
%"UNIVERSAL_GND"
"1","(-2725,800)","0","pure_quanta_power","I7";
;
CDS_LIB"pure_quanta_power"
HDL_POWER"GND";
"A"6;
%"Q_RES"
"2","(-8700,6125)","0","pure_quanta","I75";
;
LOCATION"R422"
$SEC"1"
CDS_SEC"1"
PART_NUMBER"CS22202JB07"
VALUE"2.2K"
PACK_TYPE"0402LF"
WATTAGE"1/16W"
CDS_LIB"pure_quanta"
TOLERANCE"5%"
MATERIAL"CHIP";
"A"
$PN"1"10;
"B"
$PN"2"35;
%"UNIVERSAL_POWER"
"1","(-8525,6425)","0","pure_quanta_power","I79";
;
HDL_POWER"PVDD18_S5_P0"
CDS_LIB"pure_quanta_power";
"A"10;
%"Q_RES"
"1","(-3275,1525)","0","pure_quanta","I8";
;
LOCATION"R433"
$SEC"1"
CDS_SEC"1"
MATERIAL"CHIP"
PART_NUMBER"CS62002JB18"
WATTAGE"1/16W"
TOLERANCE"5%"
VALUE"20M"
PACK_TYPE"0402LF"
CDS_LIB"pure_quanta";
"B"
$PN"2"12;
"A"
$PN"1"13;
%"UNIVERSAL_GND"
"1","(-9050,5025)","0","pure_quanta_power","I82";
;
CDS_LIB"pure_quanta_power"
HDL_POWER"GND";
"A"11;
%"CONN6_HBC1031L200D8H"
"1","(-8675,5300)","2","pure_quanta","I83";
;
LOCATION"J6"
$SEC"1"
CDS_SEC"1"
VALUE"CONN6_HBC1031-L200D-8H"
MATERIAL"IO"
PART_NUMBER"DFHD06MS263"
PART_TYPE"THLF"
CDS_LMAN_SYM_OUTLINE"-125,150,125,-150"
NEEDS_NO_SIZE"TRUE"
CDS_LIB"pure_quanta";
"6"
$PN"6"11;
"5"
$PN"5"0;
"4"
$PN"4"11;
"3"
$PN"3"37;
"2"
$PN"2"11;
"1"
$PN"1"34;
END.
